(kicad_pcb
	(version 20260206)
	(generator "pcbnew")
	(generator_version "10.0")
	(general
		(thickness 1.6)
		(legacy_teardrops no)
	)
	(paper "A4")
	(title_block
		(title "timecard-production-celestica-r4006 — R4006-B0001-02_R01.brd")
		(comment 1 "Time Appliance Project (Time Card) / footprints 448-453 of 1113")
	)
	(layers
		(0 "F.Cu" signal "TOP")
		(4 "In1.Cu" signal "L02_GND1")
		(6 "In2.Cu" signal "L03_SIG1")
		(8 "In3.Cu" signal "L04_GND2")
		(10 "In4.Cu" signal "L05_VCC1")
		(12 "In5.Cu" signal "L06_VCC2")
		(14 "In6.Cu" signal "L07_GND3")
		(16 "In7.Cu" signal "L08_SIG2")
		(18 "In8.Cu" signal "L09_GND4")
		(2 "B.Cu" signal "BOTTOM")
		(9 "F.Adhes" user "F.Adhesive")
		(11 "B.Adhes" user "B.Adhesive")
		(13 "F.Paste" user "Package Geometry/Pastemask Top")
		(15 "B.Paste" user "Package Geometry/Pastemask Bottom")
		(5 "F.SilkS" user "Ref Des/Silkscreen Top")
		(7 "B.SilkS" user "Ref Des/Silkscreen Bottom")
		(1 "F.Mask" user "Board Geometry/Soldermask Top")
		(3 "B.Mask" user "Board Geometry/Soldermask Bottom")
		(17 "Dwgs.User" user "User.Drawings")
		(19 "Cmts.User" user "User.Comments")
		(21 "Eco1.User" user "User.Eco1")
		(23 "Eco2.User" user "User.Eco2")
		(25 "Edge.Cuts" user "Board Geometry/Outline")
		(27 "Margin" user)
		(31 "F.CrtYd" user "Package Geometry/Place Bound Top")
		(29 "B.CrtYd" user "Package Geometry/Place Bound Bottom")
		(35 "F.Fab" user "Ref Des/Assembly Top")
		(33 "B.Fab" user "Ref Des/Assembly Bottom")
	)
	(footprint ""
		(layer "F.Cu")
		(at 80.772 -64.1096 180)
		(property "Reference" "C285"
			(at 10.287 19.29003 0)
			(unlocked yes)
			(layer "F.SilkS")
			(effects
				(font
					(size 0.7874 0.5842)
					(thickness 0.1524)
				)
			)
		)
		(property "Value" "VAL*"
			(at 0.0762 2.067306 180)
			(unlocked yes)
			(layer "F.Fab")
			(hide yes)
			(effects
				(font
					(size 0.7874 0.5842)
					(thickness 0.1524)
				)
			)
		)
		(property "Tolerance" "TOL*"
			(at 0.0762 3.032506 180)
			(unlocked yes)
			(layer "Cmts.User")
			(hide yes)
			(effects
				(font
					(size 0.7874 0.5842)
					(thickness 0.1524)
				)
			)
		)
		(property "User Part Number" "PARTNUM*"
			(at 0.1016 4.023106 180)
			(unlocked yes)
			(layer "Cmts.User")
			(hide yes)
			(effects
				(font
					(size 0.7874 0.5842)
					(thickness 0.1524)
				)
			)
		)
		(property "Device Type" "CAPACITOR-G105-0B104-CK,0.1UF,A"
			(at 0.0508 1.127506 180)
			(unlocked yes)
			(layer "F.Fab")
			(hide yes)
			(effects
				(font
					(size 0.7874 0.5842)
					(thickness 0.1524)
				)
			)
		)
		(duplicate_pad_numbers_are_jumpers no)
		(fp_line
			(start 1.143 0.5588)
			(end 1.143 -0.5588)
			(stroke
				(width 0.1)
				(type default)
			)
			(layer "F.SilkS")
		)
		(fp_line
			(start 1.143 -0.5588)
			(end -1.143 -0.5588)
			(stroke
				(width 0.1)
				(type default)
			)
			(layer "F.SilkS")
		)
		(fp_line
			(start -1.143 0.5588)
			(end 1.143 0.5588)
			(stroke
				(width 0.1)
				(type default)
			)
			(layer "F.SilkS")
		)
		(fp_line
			(start -1.143 -0.5588)
			(end -1.143 0.5588)
			(stroke
				(width 0.1)
				(type default)
			)
			(layer "F.SilkS")
		)
		(fp_rect
			(start 1.143 -0.5588)
			(end -1.143 0.5588)
			(stroke
				(width 0)
				(type default)
			)
			(fill no)
			(layer "F.CrtYd")
		)
		(fp_line
			(start 0.508 0.3048)
			(end 0.508 -0.3048)
			(stroke
				(width 0.1)
				(type default)
			)
			(layer "F.Fab")
		)
		(fp_line
			(start 0.508 -0.3048)
			(end -0.508 -0.3048)
			(stroke
				(width 0.1)
				(type default)
			)
			(layer "F.Fab")
		)
		(fp_line
			(start -0.508 0.3048)
			(end 0.508 0.3048)
			(stroke
				(width 0.1)
				(type default)
			)
			(layer "F.Fab")
		)
		(fp_line
			(start -0.508 -0.3048)
			(end -0.508 0.3048)
			(stroke
				(width 0.1)
				(type default)
			)
			(layer "F.Fab")
		)
		(pad "1" smd rect
			(at -0.5334 0 180)
			(size 0.7112 0.6096)
			(layers "F.Cu" "F.Mask" "F.Paste")
			(net "UNNAMED_9_BNO080LGA28_I29_CAP")
		)
		(pad "2" smd rect
			(at 0.5334 0 180)
			(size 0.7112 0.6096)
			(layers "F.Cu" "F.Mask" "F.Paste")
			(net "SG")
		)
		(zone
			(layer "F.Cu")
			(hatch none 0.5)
			(connect_pads
				(clearance 0)
			)
			(min_thickness 0.25)
			(keepout
				(tracks allowed)
				(vias not_allowed)
				(pads allowed)
				(copperpour not_allowed)
				(footprints allowed)
			)
			(placement
				(enabled no)
				(sheetname "")
			)
			(fill
				(thermal_gap 0.5)
				(thermal_bridge_width 0.5)
				(island_removal_mode 0)
			)
			(polygon
				(pts
					(xy 80.6958 -63.8048) (xy 80.8482 -63.8048) (xy 80.8482 -64.4144) (xy 80.6958 -64.4144)
				)
			)
		)
	)
	(footprint ""
		(layer "F.Cu")
		(at 124.587 -53.721 180)
		(property "Reference" "R193"
			(at -3.175 -0.29337 0)
			(unlocked yes)
			(layer "F.SilkS")
			(effects
				(font
					(size 0.7874 0.5842)
					(thickness 0.1524)
				)
			)
		)
		(property "Value" "VAL*"
			(at 0.02032 2.13233 180)
			(unlocked yes)
			(layer "F.Fab")
			(hide yes)
			(effects
				(font
					(size 0.7874 0.5842)
					(thickness 0.1524)
				)
			)
		)
		(property "Device Type" "RESISTOR-G155-14701-01,4.7KOHMA"
			(at 0.008382 1.210564 180)
			(unlocked yes)
			(layer "F.Fab")
			(hide yes)
			(effects
				(font
					(size 0.7874 0.5842)
					(thickness 0.1524)
				)
			)
		)
		(property "User Part Number" "PARTNUM*"
			(at 0.02032 4.024884 180)
			(unlocked yes)
			(layer "Cmts.User")
			(hide yes)
			(effects
				(font
					(size 0.7874 0.5842)
					(thickness 0.1524)
				)
			)
		)
		(property "Tolerance" "TOL*"
			(at 0.044704 3.05435 180)
			(unlocked yes)
			(layer "Cmts.User")
			(hide yes)
			(effects
				(font
					(size 0.7874 0.5842)
					(thickness 0.1524)
				)
			)
		)
		(duplicate_pad_numbers_are_jumpers no)
		(fp_line
			(start 1.143 0.5588)
			(end 1.143 -0.5588)
			(stroke
				(width 0.1)
				(type default)
			)
			(layer "F.SilkS")
		)
		(fp_line
			(start 1.143 -0.5588)
			(end -1.143 -0.5588)
			(stroke
				(width 0.1)
				(type default)
			)
			(layer "F.SilkS")
		)
		(fp_line
			(start -1.143 0.5588)
			(end 1.143 0.5588)
			(stroke
				(width 0.1)
				(type default)
			)
			(layer "F.SilkS")
		)
		(fp_line
			(start -1.143 -0.5588)
			(end -1.143 0.5588)
			(stroke
				(width 0.1)
				(type default)
			)
			(layer "F.SilkS")
		)
		(fp_rect
			(start -1.143 0.5588)
			(end 1.143 -0.5588)
			(stroke
				(width 0)
				(type default)
			)
			(fill no)
			(layer "F.CrtYd")
		)
		(fp_line
			(start 0.508 0.3048)
			(end 0.508 -0.3048)
			(stroke
				(width 0.1)
				(type default)
			)
			(layer "F.Fab")
		)
		(fp_line
			(start 0.508 -0.3048)
			(end -0.508 -0.3048)
			(stroke
				(width 0.1)
				(type default)
			)
			(layer "F.Fab")
		)
		(fp_line
			(start -0.508 0.3048)
			(end 0.508 0.3048)
			(stroke
				(width 0.1)
				(type default)
			)
			(layer "F.Fab")
		)
		(fp_line
			(start -0.508 -0.3048)
			(end -0.508 0.3048)
			(stroke
				(width 0.1)
				(type default)
			)
			(layer "F.Fab")
		)
		(pad "1" smd rect
			(at -0.5334 0 180)
			(size 0.7112 0.6096)
			(layers "F.Cu" "F.Mask" "F.Paste")
			(net "XP3R3V_FPGA")
		)
		(pad "2" smd rect
			(at 0.5334 0 180)
			(size 0.7112 0.6096)
			(layers "F.Cu" "F.Mask" "F.Paste")
			(net "FPGA_PROGRAM_N")
		)
		(zone
			(layer "F.Cu")
			(hatch none 0.5)
			(connect_pads
				(clearance 0)
			)
			(min_thickness 0.25)
			(keepout
				(tracks allowed)
				(vias not_allowed)
				(pads allowed)
				(copperpour not_allowed)
				(footprints allowed)
			)
			(placement
				(enabled no)
				(sheetname "")
			)
			(fill
				(thermal_gap 0.5)
				(thermal_bridge_width 0.5)
				(island_removal_mode 0)
			)
			(polygon
				(pts
					(xy 124.6632 -54.0258) (xy 124.5108 -54.0258) (xy 124.5108 -53.4162) (xy 124.6632 -53.4162)
				)
			)
		)
	)
	(footprint ""
		(layer "F.Cu")
		(at 105.6894 -59.7916)
		(property "Reference" "TP184"
			(at 3.68935 0.7874 90)
			(unlocked yes)
			(layer "F.SilkS")
			(effects
				(font
					(size 0.635 0.4064)
					(thickness 0.1524)
				)
				(justify left)
			)
		)
		(property "Value" ""
			(at 0 0 0)
			(layer "F.Fab")
			(effects
				(font
					(size 1.27 1.27)
				)
			)
		)
		(property "Device Type" "TP_PIONT-TP010CT020B030_PTH-TPA"
			(at -1.341882 0.996696 0)
			(unlocked yes)
			(layer "F.Fab")
			(hide yes)
			(effects
				(font
					(size 0.7874 0.5842)
					(thickness 0.1524)
				)
				(justify left)
			)
		)
		(duplicate_pad_numbers_are_jumpers no)
		(fp_poly
			(pts
				(arc
					(start 0.889 0)
					(mid -0.889 0)
					(end 0.889 0)
				)
			)
			(stroke
				(width 0)
				(type default)
			)
			(fill no)
			(layer "B.CrtYd")
		)
		(fp_poly
			(pts
				(arc
					(start 0.889 0)
					(mid -0.889 0)
					(end 0.889 0)
				)
			)
			(stroke
				(width 0)
				(type default)
			)
			(fill no)
			(layer "F.CrtYd")
		)
		(pad "1" thru_hole circle
			(at 0 0)
			(size 0.508 0.508)
			(drill 0.254)
			(layers "*.Cu" "*.Mask")
			(remove_unused_layers no)
			(net "IO_L22N_16")
			(clearance 0.1016)
			(padstack
				(mode front_inner_back)
				(layer "Inner"
					(shape circle)
					(size 0.508 0.508)
					(clearance 0.1016)
				)
				(layer "B.Cu"
					(shape circle)
					(size 0.762 0.762)
					(clearance -0.0254)
				)
			)
		)
	)
	(footprint ""
		(layer "F.Cu")
		(at 36.9824 -105.2068)
		(property "Reference" "R34"
			(at -4.0894 -0.92583 0)
			(unlocked yes)
			(layer "F.SilkS")
			(effects
				(font
					(size 0.7874 0.5842)
					(thickness 0.1524)
				)
			)
		)
		(property "Value" "VAL*"
			(at 0.02032 2.13233 0)
			(unlocked yes)
			(layer "F.Fab")
			(hide yes)
			(effects
				(font
					(size 0.7874 0.5842)
					(thickness 0.1524)
				)
			)
		)
		(property "Tolerance" "TOL*"
			(at 0.044704 3.05435 0)
			(unlocked yes)
			(layer "Cmts.User")
			(hide yes)
			(effects
				(font
					(size 0.7874 0.5842)
					(thickness 0.1524)
				)
			)
		)
		(property "User Part Number" "PARTNUM*"
			(at 0.02032 4.024884 0)
			(unlocked yes)
			(layer "Cmts.User")
			(hide yes)
			(effects
				(font
					(size 0.7874 0.5842)
					(thickness 0.1524)
				)
			)
		)
		(property "Device Type" "RESISTOR-G155-02402-01,24KOHM,A"
			(at 0.008382 1.210564 0)
			(unlocked yes)
			(layer "F.Fab")
			(hide yes)
			(effects
				(font
					(size 0.7874 0.5842)
					(thickness 0.1524)
				)
			)
		)
		(duplicate_pad_numbers_are_jumpers no)
		(fp_line
			(start -1.143 -0.5588)
			(end -1.143 0.5588)
			(stroke
				(width 0.1)
				(type default)
			)
			(layer "F.SilkS")
		)
		(fp_line
			(start -1.143 0.5588)
			(end 1.143 0.5588)
			(stroke
				(width 0.1)
				(type default)
			)
			(layer "F.SilkS")
		)
		(fp_line
			(start 1.143 -0.5588)
			(end -1.143 -0.5588)
			(stroke
				(width 0.1)
				(type default)
			)
			(layer "F.SilkS")
		)
		(fp_line
			(start 1.143 0.5588)
			(end 1.143 -0.5588)
			(stroke
				(width 0.1)
				(type default)
			)
			(layer "F.SilkS")
		)
		(fp_poly
			(pts
				(xy -1.143 0.5588) (xy 1.143 0.5588) (xy 1.143 -0.5588) (xy -1.143 -0.5588)
			)
			(stroke
				(width 0)
				(type default)
			)
			(fill no)
			(layer "F.CrtYd")
		)
		(fp_line
			(start -0.508 -0.3048)
			(end -0.508 0.3048)
			(stroke
				(width 0.1)
				(type default)
			)
			(layer "F.Fab")
		)
		(fp_line
			(start -0.508 0.3048)
			(end 0.508 0.3048)
			(stroke
				(width 0.1)
				(type default)
			)
			(layer "F.Fab")
		)
		(fp_line
			(start 0.508 -0.3048)
			(end -0.508 -0.3048)
			(stroke
				(width 0.1)
				(type default)
			)
			(layer "F.Fab")
		)
		(fp_line
			(start 0.508 0.3048)
			(end 0.508 -0.3048)
			(stroke
				(width 0.1)
				(type default)
			)
			(layer "F.Fab")
		)
		(pad "1" smd rect
			(at -0.5334 0)
			(size 0.7112 0.6096)
			(layers "F.Cu" "F.Mask" "F.Paste")
			(net "UNNAMED_516_CAPACITOR_I29_1")
		)
		(pad "2" smd rect
			(at 0.5334 0)
			(size 0.7112 0.6096)
			(layers "F.Cu" "F.Mask" "F.Paste")
			(net "XP5R0V_FB_R_TO_AGND")
		)
		(zone
			(layer "F.Cu")
			(hatch none 0.5)
			(connect_pads
				(clearance 0)
			)
			(min_thickness 0.25)
			(keepout
				(tracks allowed)
				(vias not_allowed)
				(pads allowed)
				(copperpour not_allowed)
				(footprints allowed)
			)
			(placement
				(enabled no)
				(sheetname "")
			)
			(fill
				(thermal_gap 0.5)
				(thermal_bridge_width 0.5)
				(island_removal_mode 0)
			)
			(polygon
				(pts
					(xy 36.9062 -104.902) (xy 37.0586 -104.902) (xy 37.0586 -105.5116) (xy 36.9062 -105.5116)
				)
			)
		)
		(zone
			(layer "F.Cu")
			(hatch none 0.5)
			(connect_pads
				(clearance 0)
			)
			(min_thickness 0.25)
			(keepout
				(tracks not_allowed)
				(vias allowed)
				(pads allowed)
				(copperpour not_allowed)
				(footprints allowed)
			)
			(placement
				(enabled no)
				(sheetname "")
			)
			(fill
				(thermal_gap 0.5)
				(thermal_bridge_width 0.5)
				(island_removal_mode 0)
			)
			(polygon
				(pts
					(xy 36.9062 -104.902) (xy 37.0586 -104.902) (xy 37.0586 -105.5116) (xy 36.9062 -105.5116)
				)
			)
		)
	)
	(footprint ""
		(layer "F.Cu")
		(at 94.107 -41.021 90)
		(property "Reference" "C137"
			(at 0 -1.48463 90)
			(unlocked yes)
			(layer "F.SilkS")
			(effects
				(font
					(size 0.7874 0.5842)
					(thickness 0.1524)
				)
			)
		)
		(property "Value" "VAL*"
			(at 0.0762 3.134106 90)
			(unlocked yes)
			(layer "F.Fab")
			(hide yes)
			(effects
				(font
					(size 0.7874 0.5842)
					(thickness 0.1524)
				)
			)
		)
		(property "Tolerance" "TOL*"
			(at 0.0762 4.048506 90)
			(unlocked yes)
			(layer "Cmts.User")
			(hide yes)
			(effects
				(font
					(size 0.7874 0.5842)
					(thickness 0.1524)
				)
			)
		)
		(property "User Part Number" "PARTNUM*"
			(at 0.1016 5.013706 90)
			(unlocked yes)
			(layer "Cmts.User")
			(hide yes)
			(effects
				(font
					(size 0.7874 0.5842)
					(thickness 0.1524)
				)
			)
		)
		(property "Device Type" "CAPACITOR-G107-0F476-AM,47UF,2A"
			(at 0.0508 2.194306 90)
			(unlocked yes)
			(layer "F.Fab")
			(hide yes)
			(effects
				(font
					(size 0.7874 0.5842)
					(thickness 0.1524)
				)
			)
		)
		(duplicate_pad_numbers_are_jumpers no)
		(fp_line
			(start 1.5748 -0.9398)
			(end -1.5748 -0.9398)
			(stroke
				(width 0.1)
				(type default)
			)
			(layer "F.SilkS")
		)
		(fp_line
			(start -1.5748 -0.9398)
			(end -1.5748 0.9398)
			(stroke
				(width 0.1)
				(type default)
			)
			(layer "F.SilkS")
		)
		(fp_line
			(start 1.5748 0.9398)
			(end 1.5748 -0.9398)
			(stroke
				(width 0.1)
				(type default)
			)
			(layer "F.SilkS")
		)
		(fp_line
			(start -1.5748 0.9398)
			(end 1.5748 0.9398)
			(stroke
				(width 0.1)
				(type default)
			)
			(layer "F.SilkS")
		)
		(fp_rect
			(start 1.5748 -0.9398)
			(end -1.5748 0.9398)
			(stroke
				(width 0)
				(type default)
			)
			(fill no)
			(layer "F.CrtYd")
		)
		(fp_line
			(start 1.016 -0.635)
			(end -1.016 -0.635)
			(stroke
				(width 0.1)
				(type default)
			)
			(layer "F.Fab")
		)
		(fp_line
			(start -1.016 -0.635)
			(end -1.016 0.635)
			(stroke
				(width 0.1)
				(type default)
			)
			(layer "F.Fab")
		)
		(fp_line
			(start 1.016 0.635)
			(end 1.016 -0.635)
			(stroke
				(width 0.1)
				(type default)
			)
			(layer "F.Fab")
		)
		(fp_line
			(start -1.016 0.635)
			(end 1.016 0.635)
			(stroke
				(width 0.1)
				(type default)
			)
			(layer "F.Fab")
		)
		(pad "1" smd rect
			(at -0.8382 0 90)
			(size 0.9652 1.3716)
			(layers "F.Cu" "F.Mask" "F.Paste")
			(net "XP1R0V_FPGA_MGTAVCC")
		)
		(pad "2" smd rect
			(at 0.8382 0 90)
			(size 0.9652 1.3716)
			(layers "F.Cu" "F.Mask" "F.Paste")
			(net "SG")
		)
		(zone
			(layer "F.Cu")
			(hatch none 0.5)
			(connect_pads
				(clearance 0)
			)
			(min_thickness 0.25)
			(keepout
				(tracks allowed)
				(vias not_allowed)
				(pads allowed)
				(copperpour not_allowed)
				(footprints allowed)
			)
			(placement
				(enabled no)
				(sheetname "")
			)
			(fill
				(thermal_gap 0.5)
				(thermal_bridge_width 0.5)
				(island_removal_mode 0)
			)
			(polygon
				(pts
					(xy 93.472 -41.2496) (xy 93.472 -40.7924) (xy 94.742 -40.7924) (xy 94.742 -41.2496)
				)
			)
		)
	)
	(footprint ""
		(layer "F.Cu")
		(at 135.4074 -97.2058 180)
		(property "Reference" "C6"
			(at 2.286 -0.42037 0)
			(unlocked yes)
			(layer "F.SilkS")
			(effects
				(font
					(size 0.7874 0.5842)
					(thickness 0.1524)
				)
			)
		)
		(property "Value" "VAL*"
			(at 0.0762 3.134106 180)
			(unlocked yes)
			(layer "F.Fab")
			(hide yes)
			(effects
				(font
					(size 0.7874 0.5842)
					(thickness 0.1524)
				)
			)
		)
		(property "Device Type" "CAPACITOR-G107-0F106-EM,10UF,2A"
			(at 0.0508 2.194306 180)
			(unlocked yes)
			(layer "F.Fab")
			(hide yes)
			(effects
				(font
					(size 0.7874 0.5842)
					(thickness 0.1524)
				)
			)
		)
		(property "User Part Number" "PARTNUM*"
			(at 0.1016 5.013706 180)
			(unlocked yes)
			(layer "Cmts.User")
			(hide yes)
			(effects
				(font
					(size 0.7874 0.5842)
					(thickness 0.1524)
				)
			)
		)
		(property "Tolerance" "TOL*"
			(at 0.0762 4.048506 180)
			(unlocked yes)
			(layer "Cmts.User")
			(hide yes)
			(effects
				(font
					(size 0.7874 0.5842)
					(thickness 0.1524)
				)
			)
		)
		(duplicate_pad_numbers_are_jumpers no)
		(fp_line
			(start 1.5748 0.9398)
			(end 1.5748 -0.9398)
			(stroke
				(width 0.1)
				(type default)
			)
			(layer "F.SilkS")
		)
		(fp_line
			(start 1.5748 -0.9398)
			(end -1.5748 -0.9398)
			(stroke
				(width 0.1)
				(type default)
			)
			(layer "F.SilkS")
		)
		(fp_line
			(start -1.5748 0.9398)
			(end 1.5748 0.9398)
			(stroke
				(width 0.1)
				(type default)
			)
			(layer "F.SilkS")
		)
		(fp_line
			(start -1.5748 -0.9398)
			(end -1.5748 0.9398)
			(stroke
				(width 0.1)
				(type default)
			)
			(layer "F.SilkS")
		)
		(fp_rect
			(start 1.5748 -0.9398)
			(end -1.5748 0.9398)
			(stroke
				(width 0)
				(type default)
			)
			(fill no)
			(layer "F.CrtYd")
		)
		(fp_line
			(start 1.016 0.635)
			(end 1.016 -0.635)
			(stroke
				(width 0.1)
				(type default)
			)
			(layer "F.Fab")
		)
		(fp_line
			(start 1.016 -0.635)
			(end -1.016 -0.635)
			(stroke
				(width 0.1)
				(type default)
			)
			(layer "F.Fab")
		)
		(fp_line
			(start -1.016 0.635)
			(end 1.016 0.635)
			(stroke
				(width 0.1)
				(type default)
			)
			(layer "F.Fab")
		)
		(fp_line
			(start -1.016 -0.635)
			(end -1.016 0.635)
			(stroke
				(width 0.1)
				(type default)
			)
			(layer "F.Fab")
		)
		(pad "1" smd rect
			(at -0.8382 0 180)
			(size 0.9652 1.3716)
			(layers "F.Cu" "F.Mask" "F.Paste")
			(net "XP12R0V_A_AVIN")
		)
		(pad "2" smd rect
			(at 0.8382 0 180)
			(size 0.9652 1.3716)
			(layers "F.Cu" "F.Mask" "F.Paste")
			(net "SG")
		)
		(zone
			(layer "F.Cu")
			(hatch none 0.5)
			(connect_pads
				(clearance 0)
			)
			(min_thickness 0.25)
			(keepout
				(tracks allowed)
				(vias not_allowed)
				(pads allowed)
				(copperpour not_allowed)
				(footprints allowed)
			)
			(placement
				(enabled no)
				(sheetname "")
			)
			(fill
				(thermal_gap 0.5)
				(thermal_bridge_width 0.5)
				(island_removal_mode 0)
			)
			(polygon
				(pts
					(xy 135.1788 -96.5708) (xy 135.636 -96.5708) (xy 135.636 -97.8408) (xy 135.1788 -97.8408)
				)
			)
		)
	)
)
